# T6G (Grand Teton) — schematic netlist excerpt (pin names and nets, part order shuffled) for the footprints in the layout excerpt that follows; sources: Cadence DE-HDL packaged netlist, KiCad conversion of 04192023_DAF0TMB3IC0_F0TG_MB_C_brd_V02_OCP.brd

PC390  Q_CAPP  270UF 16V 20% OSCON  pkg SMLF  page 218 : A = SW_P12V_AUX_PVDDCR_CPU1_P1_FLT ; B = GND
PC67  Q_CAP  0.1UF 25V 10% X7R  pkg 0402  page 200 : A = PVDDCR_CPU1_P0_VMON ; B = GND

(kicad_pcb
	(version 20260206)
	(generator "pcbnew")
	(generator_version "10.0")
	(general
		(thickness 1.6)
		(legacy_teardrops no)
	)
	(paper "A4")
	(title_block
		(title "04192023_DAF0TMB3IC0_F0TG_MB_C_brd_V02_OCP.brd")
		(comment 1 "Grand Teton / footprints 3090-3091 of 8354")
	)
	(layers
		(0 "F.Cu" signal "TOP")
		(4 "In1.Cu" signal "GND")
		(6 "In2.Cu" signal "IN1")
		(8 "In3.Cu" signal "GND1")
		(10 "In4.Cu" signal "IN2")
		(12 "In5.Cu" signal "GND2")
		(14 "In6.Cu" signal "IN3")
		(16 "In7.Cu" signal "GND3")
		(18 "In8.Cu" signal "VCC")
		(20 "In9.Cu" signal "VCC1")
		(22 "In10.Cu" signal "GND4")
		(24 "In11.Cu" signal "IN4")
		(26 "In12.Cu" signal "GND5")
		(28 "In13.Cu" signal "IN5")
		(30 "In14.Cu" signal "GND6")
		(32 "In15.Cu" signal "IN6")
		(34 "In16.Cu" signal "GND7")
		(2 "B.Cu" signal "BOTTOM")
		(9 "F.Adhes" user "F.Adhesive")
		(11 "B.Adhes" user "B.Adhesive")
		(13 "F.Paste" user "Package Geometry/Pastemask Top")
		(15 "B.Paste" user "Package Geometry/Pastemask Bottom")
		(5 "F.SilkS" user "Ref Des/Silkscreen Top")
		(7 "B.SilkS" user "Ref Des/Silkscreen Bottom")
		(1 "F.Mask" user "Board Geometry/Soldermask Top")
		(3 "B.Mask" user "Board Geometry/Soldermask Bottom")
		(17 "Dwgs.User" user "User.Drawings")
		(19 "Cmts.User" user "User.Comments")
		(21 "Eco1.User" user "User.Eco1")
		(23 "Eco2.User" user "User.Eco2")
		(25 "Edge.Cuts" user "Board Geometry/Outline")
		(27 "Margin" user)
		(31 "F.CrtYd" user "Package Geometry/Place Bound Top")
		(29 "B.CrtYd" user "Package Geometry/Place Bound Bottom")
		(35 "F.Fab" user "Ref Des/Assembly Top")
		(33 "B.Fab" user "Ref Des/Assembly Bottom")
	)
	(footprint ""
		(layer "F.Cu")
		(at 83.564476 -352.36912 90)
		(property "Reference" "PC390"
			(at -5.43179 -1.903476 0)
			(unlocked yes)
			(layer "F.SilkS")
			(effects
				(font
					(size 0.7874 0.5842)
					(thickness 0.1524)
				)
				(justify left)
			)
		)
		(property "Value" ""
			(at 0 0 90)
			(layer "F.Fab")
			(effects
				(font
					(size 1.27 1.27)
				)
			)
		)
		(duplicate_pad_numbers_are_jumpers no)
		(fp_line
			(start 3.400044 -3.400044)
			(end -2.146046 -3.400044)
			(stroke
				(width 0.1524)
				(type default)
			)
			(layer "F.SilkS")
		)
		(fp_line
			(start -2.146046 -3.400044)
			(end -3.400044 -2.146046)
			(stroke
				(width 0.1524)
				(type default)
			)
			(layer "F.SilkS")
		)
		(fp_line
			(start -3.400044 -2.146046)
			(end -3.400044 -0.9398)
			(stroke
				(width 0.1524)
				(type default)
			)
			(layer "F.SilkS")
		)
		(fp_line
			(start 3.400044 -0.9398)
			(end 3.400044 -3.400044)
			(stroke
				(width 0.1524)
				(type default)
			)
			(layer "F.SilkS")
		)
		(fp_line
			(start 3.400044 0.9398)
			(end 3.400044 3.400044)
			(stroke
				(width 0.1524)
				(type default)
			)
			(layer "F.SilkS")
		)
		(fp_line
			(start -3.400044 2.146046)
			(end -3.400044 0.9398)
			(stroke
				(width 0.1524)
				(type default)
			)
			(layer "F.SilkS")
		)
		(fp_line
			(start 3.400044 3.400044)
			(end -2.146046 3.400044)
			(stroke
				(width 0.1524)
				(type default)
			)
			(layer "F.SilkS")
		)
		(fp_line
			(start -2.146046 3.400044)
			(end -3.400044 2.146046)
			(stroke
				(width 0.1524)
				(type default)
			)
			(layer "F.SilkS")
		)
		(fp_line
			(start 3.400044 -3.400044)
			(end -3.400044 -3.400044)
			(stroke
				(width 0.1)
				(type default)
			)
			(layer "F.Fab")
		)
		(fp_line
			(start -3.400044 -3.400044)
			(end -3.400044 3.400044)
			(stroke
				(width 0.1)
				(type default)
			)
			(layer "F.Fab")
		)
		(fp_line
			(start 3.400044 3.400044)
			(end 3.400044 -3.400044)
			(stroke
				(width 0.1)
				(type default)
			)
			(layer "F.Fab")
		)
		(fp_line
			(start -3.400044 3.400044)
			(end 3.400044 3.400044)
			(stroke
				(width 0.1)
				(type default)
			)
			(layer "F.Fab")
		)
		(pad "1" smd rect
			(at -2.70002 0)
			(size 1.6002 3.5052)
			(layers "F.Cu" "F.Mask" "F.Paste")
			(net "SW_P12V_AUX_PVDDCR_CPU1_P1_FLT")
		)
		(pad "2" smd rect
			(at 2.70002 0)
			(size 1.6002 3.5052)
			(layers "F.Cu" "F.Mask" "F.Paste")
			(net "GND")
		)
	)
	(footprint ""
		(layer "F.Cu")
		(at 317.210186 -361.061 -90)
		(property "Reference" "PC67"
			(at 0 0 270)
			(layer "F.SilkS")
			(hide yes)
			(effects
				(font
					(size 1.27 1.27)
				)
			)
		)
		(property "Value" ""
			(at 0 0 270)
			(layer "F.Fab")
			(effects
				(font
					(size 1.27 1.27)
				)
			)
		)
		(duplicate_pad_numbers_are_jumpers no)
		(fp_line
			(start -0.7874 0.4064)
			(end -0.7874 -0.4064)
			(stroke
				(width 0.1524)
				(type default)
			)
			(layer "F.SilkS")
		)
		(fp_line
			(start 0.7874 0.4064)
			(end -0.7874 0.4064)
			(stroke
				(width 0.1524)
				(type default)
			)
			(layer "F.SilkS")
		)
		(fp_line
			(start -0.7874 -0.4064)
			(end 0.7874 -0.4064)
			(stroke
				(width 0.1524)
				(type default)
			)
			(layer "F.SilkS")
		)
		(fp_line
			(start 0.7874 -0.4064)
			(end 0.7874 0.4064)
			(stroke
				(width 0.1524)
				(type default)
			)
			(layer "F.SilkS")
		)
		(fp_line
			(start -0.67945 0.3048)
			(end -0.67945 -0.305054)
			(stroke
				(width 0.1)
				(type default)
			)
			(layer "F.Fab")
		)
		(fp_line
			(start -0.12065 0.3048)
			(end -0.67945 0.3048)
			(stroke
				(width 0.1)
				(type default)
			)
			(layer "F.Fab")
		)
		(fp_line
			(start 0.120396 0.3048)
			(end 0.120396 0.2794)
			(stroke
				(width 0.1)
				(type default)
			)
			(layer "F.Fab")
		)
		(fp_line
			(start 0.67945 0.3048)
			(end 0.120396 0.3048)
			(stroke
				(width 0.1)
				(type default)
			)
			(layer "F.Fab")
		)
		(fp_line
			(start -0.12065 0.2794)
			(end -0.12065 0.3048)
			(stroke
				(width 0.1)
				(type default)
			)
			(layer "F.Fab")
		)
		(fp_line
			(start 0.120396 0.2794)
			(end -0.12065 0.2794)
			(stroke
				(width 0.1)
				(type default)
			)
			(layer "F.Fab")
		)
		(fp_line
			(start -0.12065 -0.2794)
			(end 0.12065 -0.2794)
			(stroke
				(width 0.1)
				(type default)
			)
			(layer "F.Fab")
		)
		(fp_line
			(start 0.12065 -0.2794)
			(end 0.12065 -0.3048)
			(stroke
				(width 0.1)
				(type default)
			)
			(layer "F.Fab")
		)
		(fp_line
			(start 0.12065 -0.3048)
			(end 0.67945 -0.3048)
			(stroke
				(width 0.1)
				(type default)
			)
			(layer "F.Fab")
		)
		(fp_line
			(start 0.67945 -0.3048)
			(end 0.67945 0.3048)
			(stroke
				(width 0.1)
				(type default)
			)
			(layer "F.Fab")
		)
		(fp_line
			(start -0.67945 -0.305054)
			(end -0.12065 -0.305054)
			(stroke
				(width 0.1)
				(type default)
			)
			(layer "F.Fab")
		)
		(fp_line
			(start -0.12065 -0.305054)
			(end -0.12065 -0.2794)
			(stroke
				(width 0.1)
				(type default)
			)
			(layer "F.Fab")
		)
		(pad "1" smd circle
			(at -0.40005 0 270)
			(size 0 0)
			(layers "F.Cu" "F.Mask" "F.Paste")
			(net "PVDDCR_CPU1_P0_VMON")
		)
		(pad "2" smd circle
			(at 0.40005 0 270)
			(size 0 0)
			(layers "F.Cu" "F.Mask" "F.Paste")
			(net "GND")
		)
	)
)
